(kicad_pcb
	(version 20221018)
	(generator pcbnew)
	(general
    (thickness 1.62)
  )
	(paper "A4")
	(title_block
    (title "ECP5 - Datacenter Secure Control Module (DC-SCM)")
    (date "2024-07-01")
    (rev "1.2.1")
		(comment 9 "footprints 196-201 of 506")
	)
	(layers
    (0 "F.Cu" signal)
    (1 "In1.Cu" power)
    (2 "In2.Cu" signal)
    (3 "In3.Cu" power)
    (4 "In4.Cu" power)
    (5 "In5.Cu" signal)
    (6 "In6.Cu" power)
    (31 "B.Cu" signal)
    (32 "B.Adhes" user "B.Adhesive")
    (33 "F.Adhes" user "F.Adhesive")
    (34 "B.Paste" user)
    (35 "F.Paste" user)
    (36 "B.SilkS" user "B.Silkscreen")
    (37 "F.SilkS" user "F.Silkscreen")
    (38 "B.Mask" user)
    (39 "F.Mask" user)
    (40 "Dwgs.User" user "User.Drawings")
    (41 "Cmts.User" user "User.Comments")
    (42 "Eco1.User" user "User.Eco1")
    (43 "Eco2.User" user "User.Eco2")
    (44 "Edge.Cuts" user)
    (45 "Margin" user)
    (46 "B.CrtYd" user "B.Courtyard")
    (47 "F.CrtYd" user "F.Courtyard")
    (48 "B.Fab" user)
    (49 "F.Fab" user)
  )
	(footprint "antmicro-footprints:SOT-23-3" (layer "F.Cu")
    (at 72.89 165.11)
    (property "Author" "Antmicro")
    (property "License" "Apache-2.0")
    (property "MPN" "2N7002")
    (property "Manufacturer" "ON Semiconductor")
    (property "Sheetfile" "fpga-banks.kicad_sch")
    (property "Sheetname" "FPGA banks")
    (property "ki_description" "Power MOSFET, N Channel, 60 V, 115 mA, 1.2 ohm, SOT-23, Surface Mount")
    (property "ki_keywords" "SMT, TRANSISTOR, SEMICONDUCTOR, NMOS")
    (attr smd)
    (fp_text reference "Q17" (at 2.14 1.55 180) (layer "F.SilkS")
        (effects (font (size 0.7 0.7) (thickness 0.127)))
    )
    (fp_text value "2N7002" (at 0.025 3.25 180) (layer "F.Fab")
        (effects (font (size 1 1) (thickness 0.15)))
    )
    (fp_text user "Author: Antmicro" (at -1.837 5.3) (layer "F.Fab") hide
        (effects (font (size 0.7 0.7) (thickness 0.15)) (justify left bottom))
    )
    (fp_text user "License: Apache-2.0" (at -1.8 6.8) (layer "F.Fab") hide
        (effects (font (size 0.7 0.7) (thickness 0.15)) (justify left bottom))
    )
    (fp_text user "${REFERENCE}" (at -0.125 0.15 180) (layer "F.Fab")
        (effects (font (size 0.25 0.25) (thickness 0.05)))
    )
    (fp_line (start -1.45 -1.35) (end -0.85 -1.35)
      (stroke (width 0.15) (type solid)) (layer "F.SilkS"))
    (fp_line (start -0.85 -1.35) (end -0.7 -1.5)
      (stroke (width 0.15) (type solid)) (layer "F.SilkS"))
    (fp_line (start -0.7 1.5) (end -0.7 1.35)
      (stroke (width 0.15) (type solid)) (layer "F.SilkS"))
    (fp_line (start 0.7 -1.5) (end -0.7 -1.5)
      (stroke (width 0.15) (type solid)) (layer "F.SilkS"))
    (fp_line (start 0.7 -0.4) (end 0.7 -1.5)
      (stroke (width 0.15) (type solid)) (layer "F.SilkS"))
    (fp_line (start 0.7 0.4) (end 0.7 1.5)
      (stroke (width 0.15) (type solid)) (layer "F.SilkS"))
    (fp_line (start 0.7 1.5) (end -0.7 1.5)
      (stroke (width 0.15) (type solid)) (layer "F.SilkS"))
    (fp_line (start -1.75 -0.5) (end -1.75 -1.4)
      (stroke (width 0.05) (type solid)) (layer "F.CrtYd"))
    (fp_line (start -1.75 0.5) (end -0.85 0.5)
      (stroke (width 0.05) (type solid)) (layer "F.CrtYd"))
    (fp_line (start -1.75 1.4) (end -1.75 0.5)
      (stroke (width 0.05) (type solid)) (layer "F.CrtYd"))
    (fp_line (start -0.9 -1.6) (end -0.9 -1.4)
      (stroke (width 0.05) (type solid)) (layer "F.CrtYd"))
    (fp_line (start -0.9 -1.6) (end 0.825 -1.6)
      (stroke (width 0.05) (type solid)) (layer "F.CrtYd"))
    (fp_line (start -0.9 -1.4) (end -1.75 -1.4)
      (stroke (width 0.05) (type solid)) (layer "F.CrtYd"))
    (fp_line (start -0.85 -0.5) (end -1.75 -0.5)
      (stroke (width 0.05) (type solid)) (layer "F.CrtYd"))
    (fp_line (start -0.85 0.5) (end -0.85 -0.5)
      (stroke (width 0.05) (type solid)) (layer "F.CrtYd"))
    (fp_line (start -0.85 1.4) (end -1.75 1.4)
      (stroke (width 0.05) (type solid)) (layer "F.CrtYd"))
    (fp_line (start -0.85 1.65) (end -0.85 1.4)
      (stroke (width 0.05) (type solid)) (layer "F.CrtYd"))
    (fp_line (start 0.825 -1.6) (end 0.825 -0.45)
      (stroke (width 0.05) (type solid)) (layer "F.CrtYd"))
    (fp_line (start 0.825 -0.45) (end 1.75 -0.45)
      (stroke (width 0.05) (type solid)) (layer "F.CrtYd"))
    (fp_line (start 0.85 0.45) (end 0.85 1.65)
      (stroke (width 0.05) (type solid)) (layer "F.CrtYd"))
    (fp_line (start 0.85 1.65) (end -0.85 1.65)
      (stroke (width 0.05) (type solid)) (layer "F.CrtYd"))
    (fp_line (start 1.75 -0.45) (end 1.75 0.45)
      (stroke (width 0.05) (type solid)) (layer "F.CrtYd"))
    (fp_line (start 1.75 0.45) (end 0.85 0.45)
      (stroke (width 0.05) (type solid)) (layer "F.CrtYd"))
    (fp_line (start -0.712 -1.325) (end -0.712 1.523)
      (stroke (width 0.15) (type solid)) (layer "F.Fab"))
    (fp_line (start -0.712 1.519) (end 0.688 1.519)
      (stroke (width 0.15) (type solid)) (layer "F.Fab"))
    (fp_line (start -0.437 -1.526) (end -0.712 -1.325)
      (stroke (width 0.15) (type solid)) (layer "F.Fab"))
    (fp_line (start -0.437 -1.526) (end 0.688 -1.526)
      (stroke (width 0.15) (type solid)) (layer "F.Fab"))
    (fp_line (start 0.688 1.519) (end 0.688 -1.52)
      (stroke (width 0.15) (type solid)) (layer "F.Fab"))
    (pad "1" smd roundrect (at -1.1 -0.951) (size 1 0.6) (layers "F.Cu" "F.Paste" "F.Mask") (roundrect_rratio 0.15)
      (net 401 "Net-(Q17-G)") (pinfunction "G") (pintype "passive"))
    (pad "2" smd roundrect (at -1.1 0.949) (size 1 0.6) (layers "F.Cu" "F.Paste" "F.Mask") (roundrect_rratio 0.15)
      (net 1 "GND") (pinfunction "S") (pintype "passive"))
    (pad "3" smd roundrect (at 1.1 -0.0005) (size 1 0.6) (layers "F.Cu" "F.Paste" "F.Mask") (roundrect_rratio 0.15)
      (net 349 "Net-(D15-C)") (pinfunction "D") (pintype "passive"))
  )
	(footprint "antmicro-footprints:LED_0603_1608Metric_G" (layer "F.Cu")
    (at 73.32 167.87 180)
    (descr "LED SMD 0603 Green")
    (tags "LED SMD 0603 Green")
    (property "Author" "Antmicro")
    (property "Color" "Green")
    (property "License" "Apache-2.0")
    (property "MPN" "LG L29K-G2J1-24-Z")
    (property "Manufacturer" "OSRAM")
    (property "Sheetfile" "fpga-banks.kicad_sch")
    (property "Sheetname" "FPGA banks")
    (property "ki_description" "LED, Green, SMD, 0603, 20 mA, 1.7 V, 570 nm")
    (property "ki_keywords" "SMT, DIODE, SEMICONDUCTOR, LED")
    (attr smd)
    (fp_text reference "D15" (at -2.35 -0.025) (layer "F.SilkS")
        (effects (font (size 0.7 0.7) (thickness 0.127)))
    )
    (fp_text value "LED_G_0603_LG_L29K-G2J1-24-Z" (at 0 1.77) (layer "F.Fab")
        (effects (font (size 1 1) (thickness 0.15)))
    )
    (fp_text user "Author: Antmicro" (at -1.4224 4.799 180) (layer "F.Fab") hide
        (effects (font (size 0.7 0.7) (thickness 0.15)) (justify left bottom))
    )
    (fp_text user "License: Apache-2.0" (at -1.4224 3.599 180) (layer "F.Fab") hide
        (effects (font (size 0.7 0.7) (thickness 0.15)) (justify left bottom))
    )
    (fp_text user "${REFERENCE}" (at -1.4224 5.999 180) (layer "F.Fab") hide
        (effects (font (size 0.7 0.7) (thickness 0.15)) (justify left bottom))
    )
    (fp_line (start -1.18 -0.319) (end -1.18 0.321)
      (stroke (width 0.15) (type solid)) (layer "F.SilkS"))
    (fp_line (start -0.094672 0.001008) (end -0.24 0.001008)
      (stroke (width 0.1) (type solid)) (layer "F.SilkS"))
    (fp_line (start -0.094672 0.001008) (end 0.105328 -0.198992)
      (stroke (width 0.1) (type solid)) (layer "F.SilkS"))
    (fp_line (start -0.094672 0.201008) (end -0.094672 -0.198992)
      (stroke (width 0.1) (type solid)) (layer "F.SilkS"))
    (fp_line (start 0.105328 0.001008) (end 0.24 0.001)
      (stroke (width 0.1) (type solid)) (layer "F.SilkS"))
    (fp_line (start 0.105328 0.201008) (end -0.094672 0.001008)
      (stroke (width 0.1) (type solid)) (layer "F.SilkS"))
    (fp_line (start 0.105328 0.201008) (end 0.105328 -0.198992)
      (stroke (width 0.1) (type solid)) (layer "F.SilkS"))
    (fp_line (start 0.22 -0.35) (end -0.22 -0.35)
      (stroke (width 0.15) (type solid)) (layer "F.SilkS"))
    (fp_line (start 0.22 0.35) (end -0.22 0.35)
      (stroke (width 0.15) (type solid)) (layer "F.SilkS"))
    (fp_rect (start 1.25 0.65) (end -1.25 -0.65)
      (stroke (width 0.05) (type solid)) (fill none) (layer "F.CrtYd"))
    (fp_line (start -0.199 -0.202) (end -0.199 0.1)
      (stroke (width 0.15) (type solid)) (layer "F.Fab"))
    (fp_line (start -0.199 0) (end -0.597 0)
      (stroke (width 0.15) (type solid)) (layer "F.Fab"))
    (fp_line (start -0.199 0.2) (end -0.199 0.1)
      (stroke (width 0.15) (type solid)) (layer "F.Fab"))
    (fp_line (start -0.101 0) (end 0.201 0.2)
      (stroke (width 0.15) (type solid)) (layer "F.Fab"))
    (fp_line (start 0.201 -0.202) (end -0.101 0)
      (stroke (width 0.15) (type solid)) (layer "F.Fab"))
    (fp_line (start 0.201 0) (end 0.201 -0.202)
      (stroke (width 0.15) (type solid)) (layer "F.Fab"))
    (fp_line (start 0.201 0.2) (end 0.201 0)
      (stroke (width 0.15) (type solid)) (layer "F.Fab"))
    (fp_line (start 0.599 0) (end 0.201 0)
      (stroke (width 0.15) (type solid)) (layer "F.Fab"))
    (fp_rect (start 0.848 0.4) (end -0.85 -0.402)
      (stroke (width 0.15) (type solid)) (fill none) (layer "F.Fab"))
    (pad "1" smd roundrect (at -0.7 0) (size 0.8 1) (layers "F.Cu" "F.Paste" "F.Mask") (roundrect_rratio 0.2)
      (net 349 "Net-(D15-C)") (pinfunction "C") (pintype "passive"))
    (pad "2" smd roundrect (at 0.7 0) (size 0.8 1) (layers "F.Cu" "F.Paste" "F.Mask") (roundrect_rratio 0.2)
      (net 350 "Net-(D15-A)") (pinfunction "A") (pintype "passive"))
  )
	(footprint "antmicro-footprints:R_0402_1005Metric" (layer "F.Cu")
    (at 70.83 167.87)
    (descr "Resistor SMD 0402")
    (tags "resistor SMD 0402")
    (property "Author" "Antmicro")
    (property "License" "Apache-2.0")
    (property "MPN" "CR0402-FX-1001GLF")
    (property "Manufacturer" "Bourns")
    (property "Public" "False")
    (property "Sheetfile" "fpga-banks.kicad_sch")
    (property "Sheetname" "FPGA banks")
    (property "Tolerance" "1%")
    (property "Val" "1k")
    (property "ki_description" "SMD Chip Resistor, 1 kohm, ± 1%, 63 mW, 0402 [1005 Metric], Thick Film, General Purpose")
    (property "ki_keywords" "0402, SMT, RESISTOR, PASSIVE")
    (attr smd)
    (fp_text reference "R130" (at -2.32 0.03) (layer "F.SilkS")
        (effects (font (size 0.7 0.7) (thickness 0.127)))
    )
    (fp_text value "R_1k_0402" (at 0 1.17) (layer "F.Fab")
        (effects (font (size 1 1) (thickness 0.15)))
    )
    (fp_text user "${REFERENCE}" (at 0 0) (layer "F.Fab")
        (effects (font (size 0.25 0.25) (thickness 0.04)))
    )
    (fp_text user "Author: Antmicro" (at -0.95 4.169) (layer "F.Fab") hide
        (effects (font (size 0.7 0.7) (thickness 0.15)) (justify left bottom))
    )
    (fp_text user "License: Apache-2.0" (at -0.95 5.169) (layer "F.Fab") hide
        (effects (font (size 0.7 0.7) (thickness 0.15)) (justify left bottom))
    )
    (fp_rect (start -0.925 -0.47) (end 0.925 0.47)
      (stroke (width 0.05) (type default)) (fill none) (layer "F.CrtYd"))
    (fp_rect (start -0.5 -0.25) (end 0.5 0.25)
      (stroke (width 0.15) (type solid)) (fill none) (layer "F.Fab"))
    (pad "1" smd roundrect (at -0.48 0) (size 0.59 0.64) (layers "F.Cu" "F.Paste" "F.Mask") (roundrect_rratio 0.25)
      (net 2 "VCC3V3") (pintype "passive"))
    (pad "2" smd roundrect (at 0.48 0) (size 0.59 0.64) (layers "F.Cu" "F.Paste" "F.Mask") (roundrect_rratio 0.25)
      (net 350 "Net-(D15-A)") (pintype "passive"))
  )
	(footprint "antmicro-footprints:F_1206_3216Metric" (layer "F.Cu")
    (at 84.69 64.125 180)
    (property "Author" "Antmicro")
    (property "License" "Apache-2.0")
    (property "MPN" "0466003.NR ")
    (property "Manufacturer" "Littelfuse")
    (property "Sheetfile" "power-supply.kicad_sch")
    (property "Sheetname" "Power supply")
    (property "ki_description" "Fuse, Surface Mount, 3 A, Very Fast Acting, 32 V, 32 V, 1206 (3216 Metric), 466")
    (property "ki_keywords" "FUSE, PASSIVE")
    (attr smd)
    (fp_text reference "F1" (at -2.59 0.3 90) (layer "F.SilkS")
        (effects (font (size 0.7 0.7) (thickness 0.127)) (justify right))
    )
    (fp_text value "0466003.NR" (at 0.1778 2.3622) (layer "F.Fab")
        (effects (font (size 1.27 1.27) (thickness 0.15)))
    )
    (fp_text user "License: Apache-2.0" (at -1.95 5.2 180) (layer "F.Fab") hide
        (effects (font (size 0.7 0.7) (thickness 0.15)) (justify left bottom))
    )
    (fp_text user "${REFERENCE}" (at -1.95 4 180) (layer "F.Fab") hide
        (effects (font (size 0.7 0.7) (thickness 0.15)) (justify left bottom))
    )
    (fp_text user "Author: Antmicro" (at -1.95 6.4 180) (layer "F.Fab") hide
        (effects (font (size 0.7 0.7) (thickness 0.15)) (justify left bottom))
    )
    (fp_line (start 0.8 -0.899) (end -0.8 -0.899)
      (stroke (width 0.15) (type solid)) (layer "F.SilkS"))
    (fp_line (start 0.8 0.901) (end -0.8 0.901)
      (stroke (width 0.15) (type solid)) (layer "F.SilkS"))
    (fp_rect (start -2.325 -1.15) (end 2.325 1.15)
      (stroke (width 0.05) (type default)) (fill none) (layer "F.CrtYd"))
    (fp_line (start -1.677 -0.861) (end 1.624 -0.861)
      (stroke (width 0.15) (type solid)) (layer "F.Fab"))
    (fp_line (start -1.677 0.792) (end -1.677 -0.861)
      (stroke (width 0.15) (type solid)) (layer "F.Fab"))
    (fp_line (start 1.624 -0.861) (end 1.624 0.792)
      (stroke (width 0.15) (type solid)) (layer "F.Fab"))
    (fp_line (start 1.624 0.792) (end -1.677 0.792)
      (stroke (width 0.15) (type solid)) (layer "F.Fab"))
    (pad "1" smd roundrect (at -1.5 0.001 180) (size 1.15 1.8) (layers "F.Cu" "F.Paste" "F.Mask") (roundrect_rratio 0.25)
      (net 57 "P12V_AUX") (pintype "passive"))
    (pad "2" smd roundrect (at 1.5 0.001 180) (size 1.15 1.8) (layers "F.Cu" "F.Paste" "F.Mask") (roundrect_rratio 0.25)
      (net 15 "VCC12V") (pintype "passive"))
  )
	(footprint "antmicro-footprints:TP_1206_SMD_RCW-0C" (layer "F.Cu")
    (at 86.03 60.84 90)
    (property "Author" "Antmicro")
    (property "License" "Apache-2.0")
    (property "MPN" "RCW-0C")
    (property "Manufacturer" "TE Connectivity")
    (property "Sheetfile" "power-supply.kicad_sch")
    (property "Sheetname" "Power supply")
    (property "ki_description" "Circuit Probe Pad, SMD, Test Point, 1206")
    (property "ki_keywords" "1206, SMT, TESTPOINT, PASSIVE")
    (attr smd)
    (fp_text reference "TP4" (at 0.955 -3.97 90) (layer "F.SilkS")
        (effects (font (size 0.7 0.7) (thickness 0.127)))
    )
    (fp_text value "RCW-0C" (at 0 2.05 90) (layer "F.Fab")
        (effects (font (size 1 1) (thickness 0.15)))
    )
    (fp_text user "${REFERENCE}" (at 0 0 90) (layer "F.Fab")
        (effects (font (size 0.4 0.4) (thickness 0.04)))
    )
    (fp_text user "Author: Antmicro" (at -4.68 4.25 90) (layer "F.Fab") hide
        (effects (font (size 0.7 0.7) (thickness 0.15)) (justify left bottom))
    )
    (fp_text user "License: Apache-2.0" (at -4.68 5.45 90) (layer "F.Fab") hide
        (effects (font (size 0.7 0.7) (thickness 0.15)) (justify left bottom))
    )
    (fp_line (start -1.779 -0.981) (end -1.779 -0.479)
      (stroke (width 0.15) (type solid)) (layer "F.SilkS"))
    (fp_line (start -1.779 -0.981) (end -1.279 -0.981)
      (stroke (width 0.15) (type solid)) (layer "F.SilkS"))
    (fp_line (start -1.779 0.482) (end -1.779 0.98)
      (stroke (width 0.15) (type solid)) (layer "F.SilkS"))
    (fp_line (start -1.779 0.98) (end -1.279 0.98)
      (stroke (width 0.15) (type solid)) (layer "F.SilkS"))
    (fp_line (start 1.78 -0.981) (end 1.281 -0.981)
      (stroke (width 0.15) (type solid)) (layer "F.SilkS"))
    (fp_line (start 1.78 -0.981) (end 1.78 -0.479)
      (stroke (width 0.15) (type solid)) (layer "F.SilkS"))
    (fp_line (start 1.78 0.982) (end 1.281 0.982)
      (stroke (width 0.15) (type solid)) (layer "F.SilkS"))
    (fp_line (start 1.78 0.982) (end 1.78 0.482)
      (stroke (width 0.15) (type solid)) (layer "F.SilkS"))
    (fp_rect (start -2.101 -1.314) (end 2.1 1.312)
      (stroke (width 0.05) (type solid)) (fill none) (layer "F.CrtYd"))
    (fp_rect (start -1.601 -0.814) (end 1.6 0.812)
      (stroke (width 0.15) (type solid)) (fill none) (layer "F.Fab"))
    (pad "1" smd rect (at 0 0 90) (size 3.4 1.8) (layers "F.Cu" "F.Paste" "F.Mask")
      (net 57 "P12V_AUX") (pinfunction "1") (pintype "passive"))
  )
	(footprint "antmicro-footprints:TP_1206_SMD_RCW-0C" (layer "F.Cu")
    (at 83.6 60.84 90)
    (property "Author" "Antmicro")
    (property "License" "Apache-2.0")
    (property "MPN" "RCW-0C")
    (property "Manufacturer" "TE Connectivity")
    (property "Sheetfile" "power-supply.kicad_sch")
    (property "Sheetname" "Power supply")
    (property "ki_description" "Circuit Probe Pad, SMD, Test Point, 1206")
    (property "ki_keywords" "1206, SMT, TESTPOINT, PASSIVE")
    (attr smd)
    (fp_text reference "TP5" (at 0.94 -2.6 90) (layer "F.SilkS")
        (effects (font (size 0.7 0.7) (thickness 0.127)))
    )
    (fp_text value "RCW-0C" (at 0 2.05 90) (layer "F.Fab")
        (effects (font (size 1 1) (thickness 0.15)))
    )
    (fp_text user "${REFERENCE}" (at 0 0 90) (layer "F.Fab")
        (effects (font (size 0.4 0.4) (thickness 0.04)))
    )
    (fp_text user "License: Apache-2.0" (at -4.68 5.45 90) (layer "F.Fab") hide
        (effects (font (size 0.7 0.7) (thickness 0.15)) (justify left bottom))
    )
    (fp_text user "Author: Antmicro" (at -4.68 4.25 90) (layer "F.Fab") hide
        (effects (font (size 0.7 0.7) (thickness 0.15)) (justify left bottom))
    )
    (fp_line (start -1.779 -0.981) (end -1.779 -0.479)
      (stroke (width 0.15) (type solid)) (layer "F.SilkS"))
    (fp_line (start -1.779 -0.981) (end -1.279 -0.981)
      (stroke (width 0.15) (type solid)) (layer "F.SilkS"))
    (fp_line (start -1.779 0.482) (end -1.779 0.98)
      (stroke (width 0.15) (type solid)) (layer "F.SilkS"))
    (fp_line (start -1.779 0.98) (end -1.279 0.98)
      (stroke (width 0.15) (type solid)) (layer "F.SilkS"))
    (fp_line (start 1.78 -0.981) (end 1.281 -0.981)
      (stroke (width 0.15) (type solid)) (layer "F.SilkS"))
    (fp_line (start 1.78 -0.981) (end 1.78 -0.479)
      (stroke (width 0.15) (type solid)) (layer "F.SilkS"))
    (fp_line (start 1.78 0.982) (end 1.281 0.982)
      (stroke (width 0.15) (type solid)) (layer "F.SilkS"))
    (fp_line (start 1.78 0.982) (end 1.78 0.482)
      (stroke (width 0.15) (type solid)) (layer "F.SilkS"))
    (fp_rect (start -2.101 -1.314) (end 2.1 1.312)
      (stroke (width 0.05) (type solid)) (fill none) (layer "F.CrtYd"))
    (fp_rect (start -1.601 -0.814) (end 1.6 0.812)
      (stroke (width 0.15) (type solid)) (fill none) (layer "F.Fab"))
    (pad "1" smd rect (at 0 0 90) (size 3.4 1.8) (layers "F.Cu" "F.Paste" "F.Mask")
      (net 1 "GND") (pinfunction "1") (pintype "passive"))
  )
)
